FILE_TYPE = MACRO_DRAWING;
SET COLOR_WIRE YELLOW;
SET COLOR_PROP MONO;
SET COLOR_DOT WHITE;
SET COLOR_ARC YELLOW;
SET COLOR_BODY GREEN;
SET COLOR_NOTE MONO;
SET PROP_DISPLAY VALUE;
SET PAGE_NUMBER P2;
FORCEADD INTEL_CORP_BPAGE..3
(0 0);
FORCEPROP 2 LAST CUSTOM_TXT_CDS <XR_PAGE_TITLE>
J 0
(-7890 5250);
DISPLAY 0.638298 (-7890 5250);
PAINT PINK (-7890 5250);
DISPLAY INVISIBLE (-7890 5250);
FORCEPROP 1 LAST CUSTOM_TXT_CDS <CON_TC_SNM23>
J 0
(-7050 2325);
PAINT ORANGE (-7050 2325);
FORCEPROP 1 LAST CUSTOM_TXT_CDS <CON_TC_SNM55>
J 0
(-4550 3125);
PAINT ORANGE (-4550 3125);
FORCEPROP 1 LAST CUSTOM_TXT_CDS <CON_TC_SNM19>
J 0
(-7050 2725);
PAINT ORANGE (-7050 2725);
FORCEPROP 1 LAST CUSTOM_TXT_CDS <CON_TC_SNO68>
J 2
(-4650 1825);
PAINT ORANGE (-4650 1825);
FORCEPROP 1 LAST CUSTOM_TXT_CDS <CON_TC_SNM67>
J 0
(-4550 1925);
PAINT ORANGE (-4550 1925);
FORCEPROP 1 LAST CUSTOM_TXT_CDS <CON_TC_SNM66>
J 0
(-4550 2025);
PAINT ORANGE (-4550 2025);
FORCEPROP 1 LAST CUSTOM_TXT_CDS <CON_TC_SNM65>
J 0
(-4550 2125);
PAINT ORANGE (-4550 2125);
FORCEPROP 1 LAST CUSTOM_TXT_CDS <CON_TC_SNM64>
J 0
(-4550 2225);
PAINT ORANGE (-4550 2225);
FORCEPROP 1 LAST CUSTOM_TXT_CDS <CON_TC_SNM63>
J 0
(-4550 2325);
PAINT ORANGE (-4550 2325);
FORCEPROP 1 LAST CUSTOM_TXT_CDS <CON_TC_SNM62>
J 0
(-4550 2425);
PAINT ORANGE (-4550 2425);
FORCEPROP 1 LAST CUSTOM_TXT_CDS <CON_TC_SNM61>
J 0
(-4550 2525);
PAINT ORANGE (-4550 2525);
FORCEPROP 1 LAST CUSTOM_TXT_CDS <CON_TC_SNM60>
J 0
(-4550 2625);
PAINT ORANGE (-4550 2625);
FORCEPROP 1 LAST CUSTOM_TXT_CDS <CON_TC_SNM59>
J 0
(-4550 2725);
PAINT ORANGE (-4550 2725);
FORCEPROP 1 LAST CUSTOM_TXT_CDS <CON_TC_SNM57>
J 0
(-4550 2925);
PAINT ORANGE (-4550 2925);
FORCEPROP 1 LAST CUSTOM_TXT_CDS <CON_TC_SNM56>
J 0
(-4550 3025);
PAINT ORANGE (-4550 3025);
FORCEPROP 1 LAST CUSTOM_TXT_CDS <CON_TC_SNM52>
J 0
(-4550 3425);
PAINT ORANGE (-4550 3425);
FORCEPROP 1 LAST CUSTOM_TXT_CDS <CON_TC_SNM50>
J 0
(-4550 3625);
PAINT ORANGE (-4550 3625);
FORCEPROP 1 LAST CUSTOM_TXT_CDS <CON_TC_SNO48>
J 2
(-4650 3825);
PAINT ORANGE (-4650 3825);
FORCEPROP 1 LAST CUSTOM_TXT_CDS <CON_TC_SNM13>
J 0
(-7050 3325);
PAINT ORANGE (-7050 3325);
FORCEPROP 1 LAST CUSTOM_TXT_CDS <CON_TC_SNO52>
J 2
(-4650 3425);
PAINT ORANGE (-4650 3425);
FORCEPROP 1 LAST CUSTOM_TXT_CDS <CON_TC_SNM68>
J 0
(-4550 1825);
PAINT ORANGE (-4550 1825);
FORCEPROP 1 LAST CUSTOM_TXT_CDS <CON_TC_SNO71>
J 2
(-4650 1525);
PAINT ORANGE (-4650 1525);
FORCEPROP 1 LAST CUSTOM_TXT_CDS <CON_TC_SNM40>
J 0
(-7050 625);
PAINT ORANGE (-7050 625);
FORCEPROP 1 LAST CUSTOM_TXT_CDS <CON_TC_SNM1>
J 0
(-7050 4525);
PAINT ORANGE (-7050 4525);
FORCEPROP 1 LAST CUSTOM_TXT_CDS <CON_TC_SNM2>
J 0
(-7050 4425);
PAINT ORANGE (-7050 4425);
FORCEPROP 1 LAST CUSTOM_TXT_CDS <CON_TC_SNM4>
J 0
(-7050 4225);
PAINT ORANGE (-7050 4225);
FORCEPROP 1 LAST CUSTOM_TXT_CDS <CON_TC_SNM5>
J 0
(-7050 4125);
PAINT ORANGE (-7050 4125);
FORCEPROP 1 LAST CUSTOM_TXT_CDS <CON_TC_SNM6>
J 0
(-7050 4025);
PAINT ORANGE (-7050 4025);
FORCEPROP 1 LAST CUSTOM_TXT_CDS <CON_TC_SNM8>
J 0
(-7050 3825);
PAINT ORANGE (-7050 3825);
FORCEPROP 1 LAST CUSTOM_TXT_CDS <CON_TC_SNM9>
J 0
(-7050 3725);
PAINT ORANGE (-7050 3725);
FORCEPROP 1 LAST CUSTOM_TXT_CDS <CON_TC_SNM11>
J 0
(-7050 3525);
PAINT ORANGE (-7050 3525);
FORCEPROP 1 LAST CUSTOM_TXT_CDS <CON_TC_SNM12>
J 0
(-7050 3425);
PAINT ORANGE (-7050 3425);
FORCEPROP 1 LAST CUSTOM_TXT_CDS <CON_TC_SNM14>
J 0
(-7050 3225);
PAINT ORANGE (-7050 3225);
FORCEPROP 1 LAST CUSTOM_TXT_CDS <CON_TC_SNM15>
J 0
(-7050 3125);
PAINT ORANGE (-7050 3125);
FORCEPROP 1 LAST CUSTOM_TXT_CDS <CON_TC_SNM16>
J 0
(-7050 3025);
PAINT ORANGE (-7050 3025);
FORCEPROP 1 LAST CUSTOM_TXT_CDS <CON_TC_SNM17>
J 0
(-7050 2925);
PAINT ORANGE (-7050 2925);
FORCEPROP 1 LAST CUSTOM_TXT_CDS <CON_TC_SNM18>
J 0
(-7050 2825);
PAINT ORANGE (-7050 2825);
FORCEPROP 1 LAST CUSTOM_TXT_CDS <CON_TC_SNM20>
J 0
(-7050 2625);
PAINT ORANGE (-7050 2625);
FORCEPROP 1 LAST CUSTOM_TXT_CDS <CON_TC_SNM21>
J 0
(-7050 2525);
PAINT ORANGE (-7050 2525);
FORCEPROP 1 LAST CUSTOM_TXT_CDS <CON_TC_SNM22>
J 0
(-7050 2425);
PAINT ORANGE (-7050 2425);
FORCEPROP 1 LAST CUSTOM_TXT_CDS <CON_TC_SNM24>
J 0
(-7050 2225);
PAINT ORANGE (-7050 2225);
FORCEPROP 1 LAST CUSTOM_TXT_CDS <CON_TC_SNM25>
J 0
(-7050 2125);
PAINT ORANGE (-7050 2125);
FORCEPROP 1 LAST CUSTOM_TXT_CDS <CON_TC_SNM26>
J 0
(-7050 2025);
PAINT ORANGE (-7050 2025);
FORCEPROP 1 LAST CUSTOM_TXT_CDS <CON_TC_SNM27>
J 0
(-7050 1925);
PAINT ORANGE (-7050 1925);
FORCEPROP 1 LAST CUSTOM_TXT_CDS <CON_TC_SNM28>
J 0
(-7050 1825);
PAINT ORANGE (-7050 1825);
FORCEPROP 1 LAST CUSTOM_TXT_CDS <CON_TC_SNM29>
J 0
(-7050 1725);
PAINT ORANGE (-7050 1725);
FORCEPROP 1 LAST CUSTOM_TXT_CDS <CON_TC_SNM30>
J 0
(-7050 1625);
PAINT ORANGE (-7050 1625);
FORCEPROP 1 LAST CUSTOM_TXT_CDS <CON_TC_SNM31>
J 0
(-7050 1525);
PAINT ORANGE (-7050 1525);
FORCEPROP 1 LAST CUSTOM_TXT_CDS <CON_TC_SNM33>
J 0
(-7050 1325);
PAINT ORANGE (-7050 1325);
FORCEPROP 1 LAST CUSTOM_TXT_CDS <CON_TC_SNM34>
J 0
(-7050 1225);
PAINT ORANGE (-7050 1225);
FORCEPROP 1 LAST CUSTOM_TXT_CDS <CON_TC_SNM35>
J 0
(-7050 1125);
PAINT ORANGE (-7050 1125);
FORCEPROP 1 LAST CUSTOM_TXT_CDS <CON_TC_SNM36>
J 0
(-7050 1025);
PAINT ORANGE (-7050 1025);
FORCEPROP 1 LAST CUSTOM_TXT_CDS <CON_TC_SNM37>
J 0
(-7050 925);
PAINT ORANGE (-7050 925);
FORCEPROP 1 LAST CUSTOM_TXT_CDS <CON_TC_SNM38>
J 0
(-7050 825);
PAINT ORANGE (-7050 825);
FORCEPROP 1 LAST CUSTOM_TXT_CDS <CON_TC_SNM39>
J 0
(-7050 725);
PAINT ORANGE (-7050 725);
FORCEPROP 1 LAST CUSTOM_TXT_CDS <CON_TC_SNM44>
J 0
(-4550 4225);
PAINT ORANGE (-4550 4225);
FORCEPROP 1 LAST CUSTOM_TXT_CDS <CON_TC_SNM45>
J 0
(-4550 4125);
PAINT ORANGE (-4550 4125);
FORCEPROP 1 LAST CUSTOM_TXT_CDS <CON_TC_SNM46>
J 0
(-4550 4025);
PAINT ORANGE (-4550 4025);
FORCEPROP 1 LAST CUSTOM_TXT_CDS <CON_TC_SNM47>
J 0
(-4550 3925);
PAINT ORANGE (-4550 3925);
FORCEPROP 1 LAST CUSTOM_TXT_CDS <CON_TC_SNM48>
J 0
(-4550 3825);
PAINT ORANGE (-4550 3825);
FORCEPROP 1 LAST CUSTOM_TXT_CDS <CON_TC_SNM53>
J 0
(-4550 3325);
PAINT ORANGE (-4550 3325);
FORCEPROP 1 LAST CUSTOM_TXT_CDS <CON_TC_SNM54>
J 0
(-4550 3225);
PAINT ORANGE (-4550 3225);
FORCEPROP 1 LAST CUSTOM_TXT_CDS <CON_TC_SNM58>
J 0
(-4550 2825);
PAINT ORANGE (-4550 2825);
FORCEPROP 1 LAST CUSTOM_TXT_CDS <CON_TC_SNM69>
J 0
(-4550 1725);
PAINT ORANGE (-4550 1725);
FORCEPROP 1 LAST CUSTOM_TXT_CDS <CON_TC_SNM70>
J 0
(-4550 1625);
PAINT ORANGE (-4550 1625);
FORCEPROP 1 LAST CUSTOM_TXT_CDS <CON_TC_SNM71>
J 0
(-4550 1525);
PAINT ORANGE (-4550 1525);
FORCEPROP 1 LAST CUSTOM_TXT_CDS <CON_TC_SNM72>
J 0
(-4550 1425);
PAINT ORANGE (-4550 1425);
FORCEPROP 1 LAST CUSTOM_TXT_CDS <CON_TC_SNM73>
J 0
(-4550 1325);
PAINT ORANGE (-4550 1325);
FORCEPROP 1 LAST CUSTOM_TXT_CDS <CON_TC_SNM74>
J 0
(-4550 1225);
PAINT ORANGE (-4550 1225);
FORCEPROP 1 LAST CUSTOM_TXT_CDS <CON_TC_SNM75>
J 0
(-4550 1125);
PAINT ORANGE (-4550 1125);
FORCEPROP 1 LAST CUSTOM_TXT_CDS <CON_TC_SNM76>
J 0
(-4550 1025);
PAINT ORANGE (-4550 1025);
FORCEPROP 1 LAST CUSTOM_TXT_CDS <CON_TC_SNM77>
J 0
(-4550 925);
PAINT ORANGE (-4550 925);
FORCEPROP 1 LAST CUSTOM_TXT_CDS <CON_TC_SNM81>
J 0
(-2050 4525);
PAINT ORANGE (-2050 4525);
FORCEPROP 1 LAST CUSTOM_TXT_CDS <CON_TC_SNM82>
J 0
(-2050 4425);
PAINT ORANGE (-2050 4425);
FORCEPROP 1 LAST CUSTOM_TXT_CDS <CON_TC_SNM83>
J 0
(-2050 4325);
PAINT ORANGE (-2050 4325);
FORCEPROP 1 LAST CUSTOM_TXT_CDS <CON_TC_SNM84>
J 0
(-2050 4225);
PAINT ORANGE (-2050 4225);
FORCEPROP 1 LAST CUSTOM_TXT_CDS <CON_TC_SNM85>
J 0
(-2050 4125);
PAINT ORANGE (-2050 4125);
FORCEPROP 1 LAST CUSTOM_TXT_CDS <CON_TC_SNM86>
J 0
(-2050 4025);
PAINT ORANGE (-2050 4025);
FORCEPROP 1 LAST CUSTOM_TXT_CDS <CON_TC_SNM87>
J 0
(-2050 3925);
PAINT ORANGE (-2050 3925);
FORCEPROP 1 LAST CUSTOM_TXT_CDS <CON_TC_SNM88>
J 0
(-2050 3825);
PAINT ORANGE (-2050 3825);
FORCEPROP 1 LAST CUSTOM_TXT_CDS <CON_TC_SNM89>
J 0
(-2050 3725);
PAINT ORANGE (-2050 3725);
FORCEPROP 1 LAST CUSTOM_TXT_CDS <CON_TC_SNM90>
J 0
(-2050 3625);
PAINT ORANGE (-2050 3625);
FORCEPROP 1 LAST CUSTOM_TXT_CDS <CON_TC_SNM91>
J 0
(-2050 3525);
PAINT ORANGE (-2050 3525);
FORCEPROP 1 LAST CUSTOM_TXT_CDS <CON_TC_SNM92>
J 0
(-2050 3425);
PAINT ORANGE (-2050 3425);
FORCEPROP 1 LAST CUSTOM_TXT_CDS <CON_TC_SNM93>
J 0
(-2050 3325);
PAINT ORANGE (-2050 3325);
FORCEPROP 1 LAST CUSTOM_TXT_CDS <CON_TC_SNM94>
J 0
(-2050 3225);
PAINT ORANGE (-2050 3225);
FORCEPROP 1 LAST CUSTOM_TXT_CDS <CON_TC_SNM95>
J 0
(-2050 3125);
PAINT ORANGE (-2050 3125);
FORCEPROP 1 LAST CUSTOM_TXT_CDS <CON_TC_SNM96>
J 0
(-2050 3025);
PAINT ORANGE (-2050 3025);
FORCEPROP 1 LAST CUSTOM_TXT_CDS <CON_TC_SNM97>
J 0
(-2050 2925);
PAINT ORANGE (-2050 2925);
FORCEPROP 1 LAST CUSTOM_TXT_CDS <CON_TC_SNM98>
J 0
(-2050 2825);
PAINT ORANGE (-2050 2825);
FORCEPROP 1 LAST CUSTOM_TXT_CDS <CON_TC_SNM99>
J 0
(-2050 2725);
PAINT ORANGE (-2050 2725);
FORCEPROP 1 LAST CUSTOM_TXT_CDS <CON_TC_SNM100>
J 0
(-2050 2625);
PAINT ORANGE (-2050 2625);
FORCEPROP 1 LAST CUSTOM_TXT_CDS <CON_TC_SNM101>
J 0
(-2050 2525);
PAINT ORANGE (-2050 2525);
FORCEPROP 1 LAST CUSTOM_TXT_CDS <CON_TC_SNM102>
J 0
(-2050 2425);
PAINT ORANGE (-2050 2425);
FORCEPROP 1 LAST CUSTOM_TXT_CDS <CON_TC_SNM103>
J 0
(-2050 2325);
PAINT ORANGE (-2050 2325);
FORCEPROP 1 LAST CUSTOM_TXT_CDS <CON_TC_SNM104>
J 0
(-2050 2225);
PAINT ORANGE (-2050 2225);
FORCEPROP 1 LAST CUSTOM_TXT_CDS <CON_TC_SNM105>
J 0
(-2050 2125);
PAINT ORANGE (-2050 2125);
FORCEPROP 1 LAST CUSTOM_TXT_CDS <CON_TC_SNM106>
J 0
(-2050 2025);
PAINT ORANGE (-2050 2025);
FORCEPROP 1 LAST CUSTOM_TXT_CDS <CON_TC_SNM107>
J 0
(-2050 1925);
PAINT ORANGE (-2050 1925);
FORCEPROP 1 LAST CUSTOM_TXT_CDS <CON_TC_SNM108>
J 0
(-2050 1825);
PAINT ORANGE (-2050 1825);
FORCEPROP 1 LAST CUSTOM_TXT_CDS <CON_TC_SNM109>
J 0
(-2050 1725);
PAINT ORANGE (-2050 1725);
FORCEPROP 1 LAST CUSTOM_TXT_CDS <CON_TC_SNM110>
J 0
(-2050 1625);
PAINT ORANGE (-2050 1625);
FORCEPROP 1 LAST CUSTOM_TXT_CDS <CON_TC_SNM112>
J 0
(-2050 1425);
PAINT ORANGE (-2050 1425);
FORCEPROP 1 LAST CUSTOM_TXT_CDS <CON_TC_SNM114>
J 0
(-2050 1225);
PAINT ORANGE (-2050 1225);
FORCEPROP 1 LAST CUSTOM_TXT_CDS <CON_TC_SNM115>
J 0
(-2050 1125);
PAINT ORANGE (-2050 1125);
FORCEPROP 1 LAST CUSTOM_TXT_CDS <CON_TC_SNM117>
J 0
(-2050 925);
PAINT ORANGE (-2050 925);
FORCEPROP 1 LAST CUSTOM_TXT_CDS <CON_TC_SNM120>
J 0
(-2050 625);
PAINT ORANGE (-2050 625);
FORCEPROP 1 LAST CUSTOM_TXT_CDS <CON_TC_SNO1>
J 2
(-7150 4525);
PAINT ORANGE (-7150 4525);
FORCEPROP 1 LAST CUSTOM_TXT_CDS <CON_TC_SNO2>
J 2
(-7150 4425);
PAINT ORANGE (-7150 4425);
FORCEPROP 1 LAST CUSTOM_TXT_CDS <CON_TC_SNO3>
J 2
(-7150 4325);
PAINT ORANGE (-7150 4325);
FORCEPROP 1 LAST CUSTOM_TXT_CDS <CON_TC_SNO4>
J 2
(-7150 4225);
PAINT ORANGE (-7150 4225);
FORCEPROP 1 LAST CUSTOM_TXT_CDS <CON_TC_SNO5>
J 2
(-7150 4125);
PAINT ORANGE (-7150 4125);
FORCEPROP 1 LAST CUSTOM_TXT_CDS <CON_TC_SNO6>
J 2
(-7150 4025);
PAINT ORANGE (-7150 4025);
FORCEPROP 1 LAST CUSTOM_TXT_CDS <CON_TC_SNO7>
J 2
(-7150 3925);
PAINT ORANGE (-7150 3925);
FORCEPROP 1 LAST CUSTOM_TXT_CDS <CON_TC_SNO8>
J 2
(-7150 3825);
PAINT ORANGE (-7150 3825);
FORCEPROP 1 LAST CUSTOM_TXT_CDS <CON_TC_SNO9>
J 2
(-7150 3725);
PAINT ORANGE (-7150 3725);
FORCEPROP 1 LAST CUSTOM_TXT_CDS <CON_TC_SNO10>
J 2
(-7150 3625);
PAINT ORANGE (-7150 3625);
FORCEPROP 1 LAST CUSTOM_TXT_CDS <CON_TC_SNO12>
J 2
(-7150 3425);
PAINT ORANGE (-7150 3425);
FORCEPROP 1 LAST CUSTOM_TXT_CDS <CON_TC_SNO13>
J 2
(-7150 3325);
PAINT ORANGE (-7150 3325);
FORCEPROP 1 LAST CUSTOM_TXT_CDS <CON_TC_SNO14>
J 2
(-7150 3225);
PAINT ORANGE (-7150 3225);
FORCEPROP 1 LAST CUSTOM_TXT_CDS <CON_TC_SNO15>
J 2
(-7150 3125);
PAINT ORANGE (-7150 3125);
FORCEPROP 1 LAST CUSTOM_TXT_CDS <CON_TC_SNO16>
J 2
(-7150 3025);
PAINT ORANGE (-7150 3025);
FORCEPROP 1 LAST CUSTOM_TXT_CDS <CON_TC_SNO17>
J 2
(-7150 2925);
PAINT ORANGE (-7150 2925);
FORCEPROP 1 LAST CUSTOM_TXT_CDS <CON_TC_SNO18>
J 2
(-7150 2825);
PAINT ORANGE (-7150 2825);
FORCEPROP 1 LAST CUSTOM_TXT_CDS <CON_TC_SNO19>
J 2
(-7150 2725);
PAINT ORANGE (-7150 2725);
FORCEPROP 1 LAST CUSTOM_TXT_CDS <CON_TC_SNO20>
J 2
(-7150 2625);
PAINT ORANGE (-7150 2625);
FORCEPROP 1 LAST CUSTOM_TXT_CDS <CON_TC_SNO21>
J 2
(-7150 2525);
PAINT ORANGE (-7150 2525);
FORCEPROP 1 LAST CUSTOM_TXT_CDS <CON_TC_SNO22>
J 2
(-7150 2425);
PAINT ORANGE (-7150 2425);
FORCEPROP 1 LAST CUSTOM_TXT_CDS <CON_TC_SNO23>
J 2
(-7150 2325);
PAINT ORANGE (-7150 2325);
FORCEPROP 1 LAST CUSTOM_TXT_CDS <CON_TC_SNO24>
J 2
(-7150 2225);
PAINT ORANGE (-7150 2225);
FORCEPROP 1 LAST CUSTOM_TXT_CDS <CON_TC_SNO25>
J 2
(-7150 2125);
PAINT ORANGE (-7150 2125);
FORCEPROP 1 LAST CUSTOM_TXT_CDS <CON_TC_SNO26>
J 2
(-7150 2025);
PAINT ORANGE (-7150 2025);
FORCEPROP 1 LAST CUSTOM_TXT_CDS <CON_TC_SNO27>
J 2
(-7150 1925);
PAINT ORANGE (-7150 1925);
FORCEPROP 1 LAST CUSTOM_TXT_CDS <CON_TC_SNO28>
J 2
(-7150 1825);
PAINT ORANGE (-7150 1825);
FORCEPROP 1 LAST CUSTOM_TXT_CDS <CON_TC_SNO29>
J 2
(-7150 1725);
PAINT ORANGE (-7150 1725);
FORCEPROP 1 LAST CUSTOM_TXT_CDS <CON_TC_SNO30>
J 2
(-7150 1625);
PAINT ORANGE (-7150 1625);
FORCEPROP 1 LAST CUSTOM_TXT_CDS <CON_TC_SNO31>
J 2
(-7150 1525);
PAINT ORANGE (-7150 1525);
FORCEPROP 1 LAST CUSTOM_TXT_CDS <CON_TC_SNO32>
J 2
(-7150 1425);
PAINT ORANGE (-7150 1425);
FORCEPROP 1 LAST CUSTOM_TXT_CDS <CON_TC_SNO33>
J 2
(-7150 1325);
PAINT ORANGE (-7150 1325);
FORCEPROP 1 LAST CUSTOM_TXT_CDS <CON_TC_SNO34>
J 2
(-7150 1225);
PAINT ORANGE (-7150 1225);
FORCEPROP 1 LAST CUSTOM_TXT_CDS <CON_TC_SNO35>
J 2
(-7150 1125);
PAINT ORANGE (-7150 1125);
FORCEPROP 1 LAST CUSTOM_TXT_CDS <CON_TC_SNO36>
J 2
(-7150 1025);
PAINT ORANGE (-7150 1025);
FORCEPROP 1 LAST CUSTOM_TXT_CDS <CON_TC_SNO37>
J 2
(-7150 925);
PAINT ORANGE (-7150 925);
FORCEPROP 1 LAST CUSTOM_TXT_CDS <CON_TC_SNO38>
J 2
(-7150 825);
PAINT ORANGE (-7150 825);
FORCEPROP 1 LAST CUSTOM_TXT_CDS <CON_TC_SNO39>
J 2
(-7150 725);
PAINT ORANGE (-7150 725);
FORCEPROP 1 LAST CUSTOM_TXT_CDS <CON_TC_SNO40>
J 2
(-7150 625);
PAINT ORANGE (-7150 625);
FORCEPROP 1 LAST CUSTOM_TXT_CDS <CON_TC_SNO41>
J 2
(-4650 4525);
PAINT ORANGE (-4650 4525);
FORCEPROP 1 LAST CUSTOM_TXT_CDS <CON_TC_SNO42>
J 2
(-4650 4425);
PAINT ORANGE (-4650 4425);
FORCEPROP 1 LAST CUSTOM_TXT_CDS <CON_TC_SNO43>
J 2
(-4650 4325);
PAINT ORANGE (-4650 4325);
FORCEPROP 1 LAST CUSTOM_TXT_CDS <CON_TC_SNO44>
J 2
(-4650 4225);
PAINT ORANGE (-4650 4225);
FORCEPROP 1 LAST CUSTOM_TXT_CDS <CON_TC_SNO45>
J 2
(-4650 4125);
PAINT ORANGE (-4650 4125);
FORCEPROP 1 LAST CUSTOM_TXT_CDS <CON_TC_SNO46>
J 2
(-4650 4025);
PAINT ORANGE (-4650 4025);
FORCEPROP 1 LAST CUSTOM_TXT_CDS <CON_TC_SNO47>
J 2
(-4650 3925);
PAINT ORANGE (-4650 3925);
FORCEPROP 1 LAST CUSTOM_TXT_CDS <CON_TC_SNO49>
J 2
(-4650 3725);
PAINT ORANGE (-4650 3725);
FORCEPROP 1 LAST CUSTOM_TXT_CDS <CON_TC_SNO50>
J 2
(-4650 3625);
PAINT ORANGE (-4650 3625);
FORCEPROP 1 LAST CUSTOM_TXT_CDS <CON_TC_SNO51>
J 2
(-4650 3525);
PAINT ORANGE (-4650 3525);
FORCEPROP 1 LAST CUSTOM_TXT_CDS <CON_TC_SNO53>
J 2
(-4650 3325);
PAINT ORANGE (-4650 3325);
FORCEPROP 1 LAST CUSTOM_TXT_CDS <CON_TC_SNO54>
J 2
(-4650 3225);
PAINT ORANGE (-4650 3225);
FORCEPROP 1 LAST CUSTOM_TXT_CDS <CON_TC_SNO55>
J 2
(-4650 3125);
PAINT ORANGE (-4650 3125);
FORCEPROP 1 LAST CUSTOM_TXT_CDS <CON_TC_SNO56>
J 2
(-4650 3025);
PAINT ORANGE (-4650 3025);
FORCEPROP 1 LAST CUSTOM_TXT_CDS <CON_TC_SNO57>
J 2
(-4650 2925);
PAINT ORANGE (-4650 2925);
FORCEPROP 1 LAST CUSTOM_TXT_CDS <CON_TC_SNO58>
J 2
(-4650 2825);
PAINT ORANGE (-4650 2825);
FORCEPROP 1 LAST CUSTOM_TXT_CDS <CON_TC_SNO59>
J 2
(-4650 2725);
PAINT ORANGE (-4650 2725);
FORCEPROP 1 LAST CUSTOM_TXT_CDS <CON_TC_SNO60>
J 2
(-4650 2625);
PAINT ORANGE (-4650 2625);
FORCEPROP 1 LAST CUSTOM_TXT_CDS <CON_TC_SNO61>
J 2
(-4650 2525);
PAINT ORANGE (-4650 2525);
FORCEPROP 1 LAST CUSTOM_TXT_CDS <CON_TC_SNO62>
J 2
(-4650 2425);
PAINT ORANGE (-4650 2425);
FORCEPROP 1 LAST CUSTOM_TXT_CDS <CON_TC_SNO63>
J 2
(-4650 2325);
PAINT ORANGE (-4650 2325);
FORCEPROP 1 LAST CUSTOM_TXT_CDS <CON_TC_SNO64>
J 2
(-4650 2225);
PAINT ORANGE (-4650 2225);
FORCEPROP 1 LAST CUSTOM_TXT_CDS <CON_TC_SNO65>
J 2
(-4650 2125);
PAINT ORANGE (-4650 2125);
FORCEPROP 1 LAST CUSTOM_TXT_CDS <CON_TC_SNO66>
J 2
(-4650 2025);
PAINT ORANGE (-4650 2025);
FORCEPROP 1 LAST CUSTOM_TXT_CDS <CON_TC_SNO67>
J 2
(-4650 1925);
PAINT ORANGE (-4650 1925);
FORCEPROP 1 LAST CUSTOM_TXT_CDS <CON_TC_SNO69>
J 2
(-4650 1725);
PAINT ORANGE (-4650 1725);
FORCEPROP 1 LAST CUSTOM_TXT_CDS <CON_TC_SNO70>
J 2
(-4650 1625);
PAINT ORANGE (-4650 1625);
FORCEPROP 1 LAST CUSTOM_TXT_CDS <CON_TC_SNO72>
J 2
(-4650 1425);
PAINT ORANGE (-4650 1425);
FORCEPROP 1 LAST CUSTOM_TXT_CDS <CON_TC_SNO73>
J 2
(-4650 1325);
PAINT ORANGE (-4650 1325);
FORCEPROP 1 LAST CUSTOM_TXT_CDS <CON_TC_SNO74>
J 2
(-4650 1225);
PAINT ORANGE (-4650 1225);
FORCEPROP 1 LAST CUSTOM_TXT_CDS <CON_TC_SNO75>
J 2
(-4650 1125);
PAINT ORANGE (-4650 1125);
FORCEPROP 1 LAST CUSTOM_TXT_CDS <CON_TC_SNO76>
J 2
(-4650 1025);
PAINT ORANGE (-4650 1025);
FORCEPROP 1 LAST CUSTOM_TXT_CDS <CON_TC_SNO77>
J 2
(-4650 925);
PAINT ORANGE (-4650 925);
FORCEPROP 1 LAST CUSTOM_TXT_CDS <CON_TC_SNO78>
J 2
(-4650 825);
PAINT ORANGE (-4650 825);
FORCEPROP 1 LAST CUSTOM_TXT_CDS <CON_TC_SNO79>
J 2
(-4650 725);
PAINT ORANGE (-4650 725);
FORCEPROP 1 LAST CUSTOM_TXT_CDS <CON_TC_SNO80>
J 2
(-4650 625);
PAINT ORANGE (-4650 625);
FORCEPROP 1 LAST CUSTOM_TXT_CDS <CON_TC_SNO81>
J 2
(-2150 4525);
PAINT ORANGE (-2150 4525);
FORCEPROP 1 LAST CUSTOM_TXT_CDS <CON_TC_SNO82>
J 2
(-2150 4425);
PAINT ORANGE (-2150 4425);
FORCEPROP 1 LAST CUSTOM_TXT_CDS <CON_TC_SNO83>
J 2
(-2150 4325);
PAINT ORANGE (-2150 4325);
FORCEPROP 1 LAST CUSTOM_TXT_CDS <CON_TC_SNO84>
J 2
(-2150 4225);
PAINT ORANGE (-2150 4225);
FORCEPROP 1 LAST CUSTOM_TXT_CDS <CON_TC_SNO85>
J 2
(-2150 4125);
PAINT ORANGE (-2150 4125);
FORCEPROP 1 LAST CUSTOM_TXT_CDS <CON_TC_SNO86>
J 2
(-2150 4025);
PAINT ORANGE (-2150 4025);
FORCEPROP 1 LAST CUSTOM_TXT_CDS <CON_TC_SNO87>
J 2
(-2150 3925);
PAINT ORANGE (-2150 3925);
FORCEPROP 1 LAST CUSTOM_TXT_CDS <CON_TC_SNO88>
J 2
(-2150 3825);
PAINT ORANGE (-2150 3825);
FORCEPROP 1 LAST CUSTOM_TXT_CDS <CON_TC_SNO89>
J 2
(-2150 3725);
PAINT ORANGE (-2150 3725);
FORCEPROP 1 LAST CUSTOM_TXT_CDS <CON_TC_SNO90>
J 2
(-2150 3625);
PAINT ORANGE (-2150 3625);
FORCEPROP 1 LAST CUSTOM_TXT_CDS <CON_TC_SNO91>
J 2
(-2150 3525);
PAINT ORANGE (-2150 3525);
FORCEPROP 1 LAST CUSTOM_TXT_CDS <CON_TC_SNO92>
J 2
(-2150 3425);
PAINT ORANGE (-2150 3425);
FORCEPROP 1 LAST CUSTOM_TXT_CDS <CON_TC_SNO93>
J 2
(-2150 3325);
PAINT ORANGE (-2150 3325);
FORCEPROP 1 LAST CUSTOM_TXT_CDS <CON_TC_SNO94>
J 2
(-2150 3225);
PAINT ORANGE (-2150 3225);
FORCEPROP 1 LAST CUSTOM_TXT_CDS <CON_TC_SNO95>
J 2
(-2150 3125);
PAINT ORANGE (-2150 3125);
FORCEPROP 1 LAST CUSTOM_TXT_CDS <CON_TC_SNO96>
J 2
(-2150 3025);
PAINT ORANGE (-2150 3025);
FORCEPROP 1 LAST CUSTOM_TXT_CDS <CON_TC_SNO97>
J 2
(-2150 2925);
PAINT ORANGE (-2150 2925);
FORCEPROP 1 LAST CUSTOM_TXT_CDS <CON_TC_SNO98>
J 2
(-2150 2825);
PAINT ORANGE (-2150 2825);
FORCEPROP 1 LAST CUSTOM_TXT_CDS <CON_TC_SNO99>
J 2
(-2150 2725);
PAINT ORANGE (-2150 2725);
FORCEPROP 1 LAST CUSTOM_TXT_CDS <CON_TC_SNO100>
J 2
(-2150 2625);
PAINT ORANGE (-2150 2625);
FORCEPROP 1 LAST CUSTOM_TXT_CDS <CON_TC_SNO101>
J 2
(-2150 2525);
PAINT ORANGE (-2150 2525);
FORCEPROP 1 LAST CUSTOM_TXT_CDS <CON_TC_SNO102>
J 2
(-2150 2425);
PAINT ORANGE (-2150 2425);
FORCEPROP 1 LAST CUSTOM_TXT_CDS <CON_TC_SNO103>
J 2
(-2150 2325);
PAINT ORANGE (-2150 2325);
FORCEPROP 1 LAST CUSTOM_TXT_CDS <CON_TC_SNO104>
J 2
(-2150 2225);
PAINT ORANGE (-2150 2225);
FORCEPROP 1 LAST CUSTOM_TXT_CDS <CON_TC_SNO105>
J 2
(-2150 2125);
PAINT ORANGE (-2150 2125);
FORCEPROP 1 LAST CUSTOM_TXT_CDS <CON_TC_SNO107>
J 2
(-2150 1925);
PAINT ORANGE (-2150 1925);
FORCEPROP 1 LAST CUSTOM_TXT_CDS <CON_TC_SNO110>
J 2
(-2150 1625);
PAINT ORANGE (-2150 1625);
FORCEPROP 1 LAST CUSTOM_TXT_CDS <CON_TC_SNO111>
J 2
(-2150 1525);
PAINT ORANGE (-2150 1525);
FORCEPROP 1 LAST CUSTOM_TXT_CDS <CON_TC_SNO112>
J 2
(-2150 1425);
PAINT ORANGE (-2150 1425);
FORCEPROP 1 LAST CUSTOM_TXT_CDS <CON_TC_SNO113>
J 2
(-2150 1325);
PAINT ORANGE (-2150 1325);
FORCEPROP 1 LAST CUSTOM_TXT_CDS <CON_TC_SNO114>
J 2
(-2150 1225);
PAINT ORANGE (-2150 1225);
FORCEPROP 1 LAST CUSTOM_TXT_CDS <CON_TC_SNO115>
J 2
(-2150 1125);
PAINT ORANGE (-2150 1125);
FORCEPROP 1 LAST CUSTOM_TXT_CDS <CON_TC_SNO116>
J 2
(-2150 1025);
PAINT ORANGE (-2150 1025);
FORCEPROP 1 LAST CUSTOM_TXT_CDS <CON_TC_SNO117>
J 2
(-2150 925);
PAINT ORANGE (-2150 925);
FORCEPROP 1 LAST CUSTOM_TXT_CDS <CON_TC_SNO119>
J 2
(-2150 725);
PAINT ORANGE (-2150 725);
FORCEPROP 1 LAST CUSTOM_TXT_CDS <CON_TC_SNO120>
J 2
(-2150 625);
PAINT ORANGE (-2150 625);
FORCEPROP 1 LAST CUSTOM_TXT_CDS <CON_TC_SNO11>
J 2
(-7150 3525);
PAINT ORANGE (-7150 3525);
FORCEPROP 1 LAST CUSTOM_TXT_CDS <CURRENT_DESIGN_SHEET> OF <TOTAL_DESIGN_SHEETS>
J 0
(-500 25);
PAINT ORANGE (-500 25);
FORCEPROP 1 LAST CUSTOM_TXT_CDS <CON_TC_SNM10>
J 0
(-7050 3625);
PAINT ORANGE (-7050 3625);
FORCEPROP 1 LAST CUSTOM_TXT_CDS <CON_TC_SNM43>
J 0
(-4550 4325);
PAINT ORANGE (-4550 4325);
FORCEPROP 1 LAST CUSTOM_TXT_CDS <CON_TC_SNM42>
J 0
(-4550 4425);
PAINT ORANGE (-4550 4425);
FORCEPROP 1 LAST CUSTOM_TXT_CDS <CON_TC_SNM41>
J 0
(-4550 4525);
PAINT ORANGE (-4550 4525);
FORCEPROP 1 LAST CUSTOM_TXT_CDS <CON_TC_SNM49>
J 0
(-4550 3725);
PAINT ORANGE (-4550 3725);
FORCEPROP 1 LAST CUSTOM_TXT_CDS <CON_TC_SNM51>
J 0
(-4550 3525);
PAINT ORANGE (-4550 3525);
FORCEPROP 1 LAST CUSTOM_TXT_CDS <CON_TC_SNO106>
J 2
(-2150 2025);
PAINT ORANGE (-2150 2025);
FORCEPROP 1 LAST CUSTOM_TXT_CDS <CON_TC_SNO108>
J 2
(-2150 1825);
PAINT ORANGE (-2150 1825);
FORCEPROP 1 LAST CUSTOM_TXT_CDS <CON_TC_SNO109>
J 2
(-2150 1725);
PAINT ORANGE (-2150 1725);
FORCEPROP 1 LAST CUSTOM_TXT_CDS <CON_TC_SNM111>
J 0
(-2050 1525);
PAINT ORANGE (-2050 1525);
FORCEPROP 1 LAST CUSTOM_TXT_CDS <CON_TC_SNM113>
J 0
(-2050 1325);
PAINT ORANGE (-2050 1325);
FORCEPROP 1 LAST CUSTOM_TXT_CDS <CON_TC_SNM116>
J 0
(-2050 1025);
PAINT ORANGE (-2050 1025);
FORCEPROP 1 LAST CUSTOM_TXT_CDS <CON_TC_SNM118>
J 0
(-2050 825);
PAINT ORANGE (-2050 825);
FORCEPROP 1 LAST CUSTOM_TXT_CDS <CON_TC_SNM119>
J 0
(-2050 725);
PAINT ORANGE (-2050 725);
FORCEPROP 1 LAST CUSTOM_TXT_CDS <CON_TC_SNM80>
J 0
(-4550 625);
PAINT ORANGE (-4550 625);
FORCEPROP 1 LAST CUSTOM_TXT_CDS <CON_TC_SNM78>
J 0
(-4550 825);
PAINT ORANGE (-4550 825);
FORCEPROP 1 LAST CUSTOM_TXT_CDS <CON_TC_SNM32>
J 0
(-7050 1425);
PAINT ORANGE (-7050 1425);
FORCEPROP 1 LAST CUSTOM_TXT_CDS <CON_TC_SNM79>
J 0
(-4550 725);
PAINT ORANGE (-4550 725);
FORCEPROP 1 LAST CUSTOM_TXT_CDS <CON_LAST_MODIFIED>
J 0
(-1925 350);
PAINT ORANGE (-1925 350);
FORCEPROP 1 LAST CUSTOM_TXT_CDS <CON_TC_SNO118>
J 2
(-2150 825);
PAINT ORANGE (-2150 825);
FORCEPROP 1 LAST CUSTOM_TXT_CDS <CON_TC_SNM7>
J 0
(-7050 3925);
PAINT ORANGE (-7050 3925);
FORCEPROP 1 LAST CUSTOM_TXT_CDS <CON_TC_SNM3>
J 0
(-7050 4325);
PAINT ORANGE (-7050 4325);
FORCEPROP 1 LAST SCH_ADDRESS3 Santa Clara, CA 95052-8119
J 0
(-3975 25);
DISPLAY 0.617021 (-3975 25);
PAINT GREEN (-3975 25);
FORCEPROP 1 LAST SCH_ADDRESS2 P.O. BOX 58119
J 0
(-3975 75);
DISPLAY 0.617021 (-3975 75);
PAINT GREEN (-3975 75);
FORCEPROP 1 LAST SCH_TITLE INDEX (1 OF 3)
J 0
(-7950 50);
DISPLAY 1.212766 (-7950 50);
PAINT ORANGE (-7950 50);
FORCEPROP 2 LAST SCH_NUMBER H4694802
J 0
(-1300 150);
DISPLAY 1.212766 (-1300 150);
PAINT YELLOW (-1300 150);
FORCEPROP 2 LAST SCH_DEPT BESD
J 1
(-4450 100);
DISPLAY 1.212766 (-4450 100);
PAINT YELLOW (-4450 100);
FORCEPROP 2 LAST SCH_REV 2.420
J 0
(-250 150);
DISPLAY 0.978723 (-250 150);
PAINT YELLOW (-250 150);
FORCEPROP 1 LAST SCH_ADDRESS1 2200 Mission College Blvd.
J 0
(-3975 125);
DISPLAY 0.617021 (-3975 125);
PAINT GREEN (-3975 125);
FORCEPROP 2 LAST PAGE_BORDER TRUE
J 0
(-7890 5250);
DISPLAY 0.638298 (-7890 5250);
PAINT PINK (-7890 5250);
DISPLAY INVISIBLE (-7890 5250);
FORCEPROP 2 LAST CDS_LIB mstr_symbols
J 0
(0 0);
PAINT ORANGE (0 0);
DISPLAY INVISIBLE (0 0);
FORCEPROP 1 LAST TOC_SYMBOL TRUE
J 0
(-7950 5050);
PAINT ORANGE (-7950 5050);
DISPLAY INVISIBLE (-7950 5050);
FORCEPROP 1 LAST COMMENT_BODY TRUE
J 0
(12 12);
DISPLAY 0.468085 (12 12);
PAINT GREEN (12 12);
DISPLAY INVISIBLE (12 12);
FORCEPROP 1 LAST CDS_CON_LAST_MODIFIED Tue Dec 01 11:47:54 2015
J 0
(-1425 325);
PAINT ORANGE (-1425 325);
DISPLAY INVISIBLE (-1425 325);
FORCEPROP 2 LAST CDS_XR_PAGE_TITLE CR-2 : @BASEBOARD_FAB2_LIB.BASEBOARD_FAB2(SCH_1):PAGE2
J 0
(-7890 5250);
DISPLAY 0.638298 (-7890 5250);
PAINT PINK (-7890 5250);
DISPLAY INVISIBLE (-7890 5250);
QUIT
